# S9S_MB_2U (Grand Teton) — schematic netlist excerpt (pin names and nets, part order shuffled) for the footprints in the layout excerpt that follows; sources: Cadence DE-HDL packaged netlist, KiCad conversion of 03242023_DA0F0TMBIJ0_F0T_Motherboard_J_brd_V01_OCP.brd

J20  SCONN288_ADR50017P087CC  SCONN288_ADR50017-P087CC IO  pkg DDR288S_1-1VXB  page 101
  VIN_BULK0  = P12V_S3_AUX_CPU1_NVDIMM
  RFU0  = TP_CHB_CPU1_DIMM2_FRU_0
  VIN_MGMT  = P3V3_AUX
  HSCL  = I3C_SPD_DDRABCD_CPU1_LVC1_SCL_3
  HSDA  = I3C_SPD_DDRABCD_CPU1_LVC1_SDA
  VSS0  = GND
  DQ0_A  = M_B_CPU1_SA_DQ<0>
  VSS1  = GND
  DQ1_A  = M_B_CPU1_SA_DQ<1>
  VSS2  = GND
  DQS0_A_T  = M_B_CPU1_SA_DQS_DP<0>
  DQS0_A_C  = M_B_CPU1_SA_DQS_DN<0>
  VSS3  = GND
  DQ4_A  = M_B_CPU1_SA_DQ<4>
  VSS4  = GND
  DQ5_A  = M_B_CPU1_SA_DQ<5>
  VSS5  = GND
  DQ8_A  = M_B_CPU1_SA_DQ<8>
  VSS6  = GND
  DQ9_A  = M_B_CPU1_SA_DQ<9>
  VSS7  = GND
  DQS1_A_T  = M_B_CPU1_SA_DQS_DP<1>
  DQS1_A_C  = M_B_CPU1_SA_DQS_DN<1>
  VSS8  = GND
  DQ12_A  = M_B_CPU1_SA_DQ<12>
  VSS9  = GND
  DQ13_A  = M_B_CPU1_SA_DQ<13>
  VSS10  = GND
  DQ16_A  = M_B_CPU1_SA_DQ<16>
  VSS11  = GND
  DQ17_A  = M_B_CPU1_SA_DQ<17>
  VSS12  = GND
  DQS2_A_T  = M_B_CPU1_SA_DQS_DP<2>
  DQS2_A_C  = M_B_CPU1_SA_DQS_DN<2>
  VSS13  = GND
  DQ20_A  = M_B_CPU1_SA_DQ<20>
  VSS14  = GND
  DQ21_A  = M_B_CPU1_SA_DQ<21>
  VSS15  = GND
  DQ24_A  = M_B_CPU1_SA_DQ<24>
  VSS16  = GND
  DQ25_A  = M_B_CPU1_SA_DQ<25>
  VSS17  = GND
  DQS3_A_T  = M_B_CPU1_SA_DQS_DP<3>
  DQS3_A_C  = M_B_CPU1_SA_DQS_DN<3>
  VSS18  = GND
  DQ28_A  = M_B_CPU1_SA_DQ<28>
  VSS19  = GND
  DQ29_A  = M_B_CPU1_SA_DQ<29>
  VSS20  = GND
  CB0_A  = M_B_CPU1_SA_CB<0>
  VSS21  = GND
  CB1_A  = M_B_CPU1_SA_CB<1>
  VSS22  = GND
  DQS4_A_T  = M_B_CPU1_SA_DQS_DP<4>
  DQS4_A_C  = M_B_CPU1_SA_DQS_DN<4>
  VSS23  = GND
  CB4_A  = M_B_CPU1_SA_CB<4>
  VSS24  = GND
  CB5_A  = M_B_CPU1_SA_CB<5>
  VSS25  = GND
  ALERT_N  = M_B_CPU1_ALERT_N
  VSS26  = GND
  CS0_A_N  = M_B_CPU1_SA_CS_N<2>
  VSS27  = GND
  CA0_A  = M_B_CPU1_SA_CA<0>
  VSS28  = GND
  CA2_A  = M_B_CPU1_SA_CA<2>
  VSS29  = GND
  CA4_A  = M_B_CPU1_SA_CA<4>
  VSS30  = GND
  CA6_A  = M_B_CPU1_SA_CA<6>
  VSS31  = GND
  PAR_A  = M_B_CPU1_SA_PAR
  VSS32  = GND
  CA0_B  = M_B_CPU1_SB_CA<0>
  VSS33  = GND
  CA2_B  = M_B_CPU1_SB_CA<2>
  VSS34  = GND
  CA4_B  = M_B_CPU1_SB_CA<4>
  VSS35  = GND
  CA6_B  = M_B_CPU1_SB_CA<6>
  VSS36  = GND
  CS0_B_N  = M_B_CPU1_SB_CS_N<2>
  VSS37  = GND
  \lbd||rsp_a_n\  = M_B_CPU1_SA_RSP<1>
  \lbs||rsp_b_n\  = M_B_CPU1_SB_RSP<1>
  VSS38  = GND
  CB4_B  = M_B_CPU1_SB_CB<4>
  VSS39  = GND
  CB5_B  = M_B_CPU1_SB_CB<5>
  VSS40  = GND
  \dqs9_b_t||tdqs9_b_t||dbi4_b_n\  = M_B_CPU1_SB_DQS_DP<9>
  \dqs9_b_c||tdqs9_b_c\  = M_B_CPU1_SB_DQS_DN<9>
  VSS41  = GND
  CB0_B  = M_B_CPU1_SB_CB<0>
  VSS42  = GND
  CB1_B  = M_B_CPU1_SB_CB<1>
  VSS43  = GND
  DQ0_B  = M_B_CPU1_SB_DQ<0>
  VSS44  = GND
  DQ1_B  = M_B_CPU1_SB_DQ<1>
  VSS45  = GND
  DQS0_B_T  = M_B_CPU1_SB_DQS_DP<0>
  DQS0_B_C  = M_B_CPU1_SB_DQS_DN<0>
  VSS46  = GND
  DQ4_B  = M_B_CPU1_SB_DQ<4>
  VSS47  = GND
  DQ5_B  = M_B_CPU1_SB_DQ<5>
  VSS48  = GND
  DQ8_B  = M_B_CPU1_SB_DQ<8>
  VSS49  = GND
  DQ9_B  = M_B_CPU1_SB_DQ<9>
  VSS50  = GND
  DQS1_B_T  = M_B_CPU1_SB_DQS_DP<1>
  DQS1_B_C  = M_B_CPU1_SB_DQS_DN<1>
  VSS51  = GND
  DQ12_B  = M_B_CPU1_SB_DQ<12>
  VSS52  = GND
  DQ13_B  = M_B_CPU1_SB_DQ<13>
  VSS53  = GND
  DQ16_B  = M_B_CPU1_SB_DQ<16>
  VSS54  = GND
  DQ17_B  = M_B_CPU1_SB_DQ<17>
  VSS55  = GND
  DQS2_B_T  = M_B_CPU1_SB_DQS_DP<2>
  DQS2_B_C  = M_B_CPU1_SB_DQS_DN<2>
  VSS56  = GND
  DQ20_B  = M_B_CPU1_SB_DQ<20>
  VSS57  = GND
  DQ21_B  = M_B_CPU1_SB_DQ<21>
  VSS58  = GND
  DQ24_B  = M_B_CPU1_SB_DQ<24>
  VSS59  = GND
  DQ25_B  = M_B_CPU1_SB_DQ<25>
  VSS60  = GND
  DQS3_B_T  = M_B_CPU1_SB_DQS_DP<3>
  DQS3_B_C  = M_B_CPU1_SB_DQS_DN<3>
  VSS61  = GND
  DQ28_B  = M_B_CPU1_SB_DQ<28>
  VSS62  = GND
  DQ29_B  = M_B_CPU1_SB_DQ<29>
  VSS63  = GND
  RFU1  = TP_CHB_CPU1_DIMM2_FRU_1
  VIN_BULK1  = P12V_S3_AUX_CPU1_NVDIMM
  VIN_BULK2  = P12V_S3_AUX_CPU1_NVDIMM
  \pwr_good||fail_n\  = PWRGD_CHB_CPU1_DIMM2
  HSA  = PD_CHB_CPU1_DIMM2_SAA
  RFU2  = TP_CHB_CPU1_DIMM2_FRU_2
  RFU3  = TP_CHB_CPU1_DIMM2_FRU_3
  VSS64  = GND
  DQ2_A  = M_B_CPU1_SA_DQ<2>
  VSS65  = GND
  DQ3_A  = M_B_CPU1_SA_DQ<3>
  VSS66  = GND
  \dqs5_a_c||tdqs5_a_c||dqs5_a_t||tdqs5_a_t\  = M_B_CPU1_SA_DQS_DN<5>
  \dqs5_a_t||tdqs5_a_t\  = M_B_CPU1_SA_DQS_DP<5>
  VSS67  = GND
  DQ6_A  = M_B_CPU1_SA_DQ<6>
  VSS68  = GND
  DQ7_A  = M_B_CPU1_SA_DQ<7>
  VSS69  = GND
  DQ10_A  = M_B_CPU1_SA_DQ<10>
  VSS70  = GND
  DQ11_A  = M_B_CPU1_SA_DQ<11>
  VSS71  = GND
  \dqs6_a_c||tdqs6_a_c||dqs6_a_t||tdqs6_a_t\  = M_B_CPU1_SA_DQS_DN<6>
  \dqs6_a_t||tdqs6_a_t\  = M_B_CPU1_SA_DQS_DP<6>
  VSS72  = GND
  DQ14_A  = M_B_CPU1_SA_DQ<14>
  VSS73  = GND
  DQ15_A  = M_B_CPU1_SA_DQ<15>
  VSS74  = GND
  DQ18_A  = M_B_CPU1_SA_DQ<18>
  VSS75  = GND
  DQ19_A  = M_B_CPU1_SA_DQ<19>
  VSS76  = GND
  \dqs7_a_c||tdqs7_a_c\  = M_B_CPU1_SA_DQS_DN<7>
  \dqs7_a_t||tdqs7_a_t\  = M_B_CPU1_SA_DQS_DP<7>
  VSS77  = GND
  DQ22_A  = M_B_CPU1_SA_DQ<22>
  VSS78  = GND
  DQ23_A  = M_B_CPU1_SA_DQ<23>
  VSS79  = GND
  DQ26_A  = M_B_CPU1_SA_DQ<26>
  VSS80  = GND
  DQ27_A  = M_B_CPU1_SA_DQ<27>
  VSS81  = GND
  \dqs8_a_c||tdqs8_a_c\  = M_B_CPU1_SA_DQS_DN<8>
  \dqs8_a_t||tdqs8_a_t\  = M_B_CPU1_SA_DQS_DP<8>
  VSS82  = GND
  DQ30_A  = M_B_CPU1_SA_DQ<30>
  VSS83  = GND
  DQ31_A  = M_B_CPU1_SA_DQ<31>
  VSS84  = GND
  CB2_A  = M_B_CPU1_SA_CB<2>
  VSS85  = GND
  CB3_A  = M_B_CPU1_SA_CB<3>
  VSS86  = GND
  \dqs9_a_c||tdqs9_a_c\  = M_B_CPU1_SA_DQS_DN<9>
  \dqs9_a_t||tdqs9_a_t\  = M_B_CPU1_SA_DQS_DP<9>
  VSS87  = GND
  CB6_A  = M_B_CPU1_SA_CB<6>
  VSS88  = GND
  CB7_A  = M_B_CPU1_SA_CB<7>
  VSS89  = GND
  RESET_N  = RST_M_AB_CPU1_FPGA_N
  VSS90  = GND
  CS1_A_N  = M_B_CPU1_SA_CS_N<3>
  VSS91  = GND
  CA1_A  = M_B_CPU1_SA_CA<1>
  VSS92  = GND
  CA3_A  = M_B_CPU1_SA_CA<3>
  VSS93  = GND
  CA5_A  = M_B_CPU1_SA_CA<5>
  VSS94  = GND
  CK_T  = M_B_CPU1_CLK_DP<1>
  CK_C  = M_B_CPU1_CLK_DN<1>
  VSS95  = GND
  RFU4  = TP_CHB_CPU1_DIMM2_FRU_4
  CA1_B  = M_B_CPU1_SB_CA<1>
  VSS96  = GND
  CA3_B  = M_B_CPU1_SB_CA<3>
  VSS97  = GND
  CA5_B  = M_B_CPU1_SB_CA<5>
  VSS98  = GND
  PAR_B  = M_B_CPU1_SB_PAR
  VSS99  = GND
  CS1_B_N  = M_B_CPU1_SB_CS_N<3>
  VSS100  = GND
  RFU5  = TP_CHB_CPU1_DIMM2_FRU_5
  RFU6  = TP_CHB_CPU1_DIMM2_FRU_6
  VSS101  = GND
  CB6_B  = M_B_CPU1_SB_CB<6>
  VSS102  = GND
  CB7_B  = M_B_CPU1_SB_CB<7>
  VSS103  = GND
  DQS4_B_C  = M_B_CPU1_SB_DQS_DN<4>
  DQS4_B_T  = M_B_CPU1_SB_DQS_DP<4>
  VSS104  = GND
  CB2_B  = M_B_CPU1_SB_CB<2>
  VSS105  = GND
  CB3_B  = M_B_CPU1_SB_CB<3>
  VSS106  = GND
  DQ2_B  = M_B_CPU1_SB_DQ<2>
  VSS107  = GND
  DQ3_B  = M_B_CPU1_SB_DQ<3>
  VSS108  = GND
  \dqs5_b_c||tdqs5_b_c\  = M_B_CPU1_SB_DQS_DN<5>
  \dqs5_b_t||tdqs5_b_t\  = M_B_CPU1_SB_DQS_DP<5>
  VSS109  = GND
  DQ6_B  = M_B_CPU1_SB_DQ<6>
  VSS110  = GND
  DQ7_B  = M_B_CPU1_SB_DQ<7>
  VSS111  = GND
  DQ10_B  = M_B_CPU1_SB_DQ<10>
  VSS112  = GND
  DQ11_B  = M_B_CPU1_SB_DQ<11>
  VSS113  = GND
  \dqs6_b_c||tdqs6_b_c\  = M_B_CPU1_SB_DQS_DN<6>
  \dqs6_b_t||tdqs6_b_t\  = M_B_CPU1_SB_DQS_DP<6>
  VSS114  = GND
  DQ14_B  = M_B_CPU1_SB_DQ<14>
  VSS115  = GND
  DQ15_B  = M_B_CPU1_SB_DQ<15>
  VSS116  = GND
  DQ18_B  = M_B_CPU1_SB_DQ<18>
  VSS117  = GND
  DQ19_B  = M_B_CPU1_SB_DQ<19>
  VSS118  = GND
  \dqs7_b_c||tdqs7_b_c\  = M_B_CPU1_SB_DQS_DN<7>
  \dqs7_b_t||tdqs7_b_t\  = M_B_CPU1_SB_DQS_DP<7>
  VSS119  = GND
  DQ22_B  = M_B_CPU1_SB_DQ<22>
  VSS120  = GND
  DQ23_B  = M_B_CPU1_SB_DQ<23>
  VSS121  = GND
  DQ26_B  = M_B_CPU1_SB_DQ<26>
  VSS122  = GND
  DQ27_B  = M_B_CPU1_SB_DQ<27>
  VSS123  = GND
  \dqs8_b_c||tdqs8_b_c\  = M_B_CPU1_SB_DQS_DN<8>
  \dqs8_b_t||tdqs8_b_t\  = M_B_CPU1_SB_DQS_DP<8>
  VSS124  = GND
  DQ30_B  = M_B_CPU1_SB_DQ<30>
  VSS125  = GND
  DQ31_B  = M_B_CPU1_SB_DQ<31>
  VSS126  = GND
  G1  = GND
  G2  = GND
  G3  = GND

(kicad_pcb
	(version 20260206)
	(generator "pcbnew")
	(generator_version "10.0")
	(general
		(thickness 1.6)
		(legacy_teardrops no)
	)
	(paper "A4")
	(title_block
		(title "03242023_DA0F0TMBIJ0_F0T_Motherboard_J_brd_V01_OCP.brd")
		(comment 1 "Grand Teton / footprint 1508 of 6105 (J20), pads 46-91 of 291")
	)
	(layers
		(0 "F.Cu" signal "TOP")
		(4 "In1.Cu" signal "GND")
		(6 "In2.Cu" signal "IN1")
		(8 "In3.Cu" signal "GND1")
		(10 "In4.Cu" signal "IN2")
		(12 "In5.Cu" signal "GND2")
		(14 "In6.Cu" signal "IN3")
		(16 "In7.Cu" signal "GND3")
		(18 "In8.Cu" signal "VCC")
		(20 "In9.Cu" signal "VCC1")
		(22 "In10.Cu" signal "GND4")
		(24 "In11.Cu" signal "IN4")
		(26 "In12.Cu" signal "GND5")
		(28 "In13.Cu" signal "IN5")
		(30 "In14.Cu" signal "GND6")
		(32 "In15.Cu" signal "IN6")
		(34 "In16.Cu" signal "GND7")
		(2 "B.Cu" signal "BOTTOM")
		(9 "F.Adhes" user "F.Adhesive")
		(11 "B.Adhes" user "B.Adhesive")
		(13 "F.Paste" user "Package Geometry/Pastemask Top")
		(15 "B.Paste" user "Package Geometry/Pastemask Bottom")
		(5 "F.SilkS" user "Ref Des/Silkscreen Top")
		(7 "B.SilkS" user "Ref Des/Silkscreen Bottom")
		(1 "F.Mask" user "Board Geometry/Soldermask Top")
		(3 "B.Mask" user "Board Geometry/Soldermask Bottom")
		(17 "Dwgs.User" user "User.Drawings")
		(19 "Cmts.User" user "User.Comments")
		(21 "Eco1.User" user "User.Eco1")
		(23 "Eco2.User" user "User.Eco2")
		(25 "Edge.Cuts" user "Board Geometry/Outline")
		(27 "Margin" user)
		(31 "F.CrtYd" user "Package Geometry/Place Bound Top")
		(29 "B.CrtYd" user "Package Geometry/Place Bound Bottom")
		(35 "F.Fab" user "Ref Des/Assembly Top")
		(33 "B.Fab" user "Ref Des/Assembly Bottom")
	)
	(footprint ""
		(layer "F.Cu")
		(at 47.90948 -258.091686)
		(property "Reference" "J20"
			(at -2.74066 -81.678272 0)
			(unlocked yes)
			(layer "F.SilkS")
			(effects
				(font
					(size 0.7874 0.5842)
					(thickness 0.1524)
				)
				(justify left)
			)
		)
		(property "Value" ""
			(at 0 0 0)
			(layer "F.Fab")
			(effects
				(font
					(size 1.27 1.27)
				)
			)
		)
		(duplicate_pad_numbers_are_jumpers no)
		(pad "46" smd rect
			(at -2.050034 -25.07488 270)
			(size 0.519938 1.4986)
			(layers "F.Cu" "F.Mask" "F.Paste")
			(net "GND")
		)
		(pad "47" smd rect
			(at -2.050034 -24.224996 270)
			(size 0.519938 1.4986)
			(layers "F.Cu" "F.Mask" "F.Paste")
			(net "M_B_CPU1_SA_DQ<28>")
		)
		(pad "48" smd rect
			(at -2.050034 -23.375112 270)
			(size 0.519938 1.4986)
			(layers "F.Cu" "F.Mask" "F.Paste")
			(net "GND")
		)
		(pad "49" smd rect
			(at -2.050034 -22.524974 270)
			(size 0.519938 1.4986)
			(layers "F.Cu" "F.Mask" "F.Paste")
			(net "M_B_CPU1_SA_DQ<29>")
		)
		(pad "50" smd rect
			(at -2.050034 -21.67509 270)
			(size 0.519938 1.4986)
			(layers "F.Cu" "F.Mask" "F.Paste")
			(net "GND")
		)
		(pad "51" smd rect
			(at -2.050034 -20.824952 270)
			(size 0.519938 1.4986)
			(layers "F.Cu" "F.Mask" "F.Paste")
			(net "M_B_CPU1_SA_CB<0>")
		)
		(pad "52" smd rect
			(at -2.050034 -19.975068 270)
			(size 0.519938 1.4986)
			(layers "F.Cu" "F.Mask" "F.Paste")
			(net "GND")
		)
		(pad "53" smd rect
			(at -2.050034 -19.12493 270)
			(size 0.519938 1.4986)
			(layers "F.Cu" "F.Mask" "F.Paste")
			(net "M_B_CPU1_SA_CB<1>")
		)
		(pad "54" smd rect
			(at -2.050034 -18.275046 270)
			(size 0.519938 1.4986)
			(layers "F.Cu" "F.Mask" "F.Paste")
			(net "GND")
		)
		(pad "55" smd rect
			(at -2.050034 -17.424908 270)
			(size 0.519938 1.4986)
			(layers "F.Cu" "F.Mask" "F.Paste")
			(net "M_B_CPU1_SA_DQS_DP<4>")
		)
		(pad "56" smd rect
			(at -2.050034 -16.575024 270)
			(size 0.519938 1.4986)
			(layers "F.Cu" "F.Mask" "F.Paste")
			(net "M_B_CPU1_SA_DQS_DN<4>")
		)
		(pad "57" smd rect
			(at -2.050034 -15.724886 270)
			(size 0.519938 1.4986)
			(layers "F.Cu" "F.Mask" "F.Paste")
			(net "GND")
		)
		(pad "58" smd rect
			(at -2.050034 -14.875002 270)
			(size 0.519938 1.4986)
			(layers "F.Cu" "F.Mask" "F.Paste")
			(net "M_B_CPU1_SA_CB<4>")
		)
		(pad "59" smd rect
			(at -2.050034 -14.025118 270)
			(size 0.519938 1.4986)
			(layers "F.Cu" "F.Mask" "F.Paste")
			(net "GND")
		)
		(pad "60" smd rect
			(at -2.050034 -13.17498 270)
			(size 0.519938 1.4986)
			(layers "F.Cu" "F.Mask" "F.Paste")
			(net "M_B_CPU1_SA_CB<5>")
		)
		(pad "61" smd rect
			(at -2.050034 -12.325096 270)
			(size 0.519938 1.4986)
			(layers "F.Cu" "F.Mask" "F.Paste")
			(net "GND")
		)
		(pad "62" smd rect
			(at -2.050034 -11.474958 270)
			(size 0.519938 1.4986)
			(layers "F.Cu" "F.Mask" "F.Paste")
			(net "M_B_CPU1_ALERT_N")
		)
		(pad "63" smd rect
			(at -2.050034 -10.625074 270)
			(size 0.519938 1.4986)
			(layers "F.Cu" "F.Mask" "F.Paste")
			(net "GND")
		)
		(pad "64" smd rect
			(at -2.050034 -9.774936 270)
			(size 0.519938 1.4986)
			(layers "F.Cu" "F.Mask" "F.Paste")
			(net "M_B_CPU1_SA_CS_N<2>")
		)
		(pad "65" smd rect
			(at -2.050034 -8.925052 270)
			(size 0.519938 1.4986)
			(layers "F.Cu" "F.Mask" "F.Paste")
			(net "GND")
		)
		(pad "66" smd rect
			(at -2.050034 -8.074914 270)
			(size 0.519938 1.4986)
			(layers "F.Cu" "F.Mask" "F.Paste")
			(net "M_B_CPU1_SA_CA<0>")
		)
		(pad "67" smd rect
			(at -2.050034 -7.22503 270)
			(size 0.519938 1.4986)
			(layers "F.Cu" "F.Mask" "F.Paste")
			(net "GND")
		)
		(pad "68" smd rect
			(at -2.050034 -6.374892 270)
			(size 0.519938 1.4986)
			(layers "F.Cu" "F.Mask" "F.Paste")
			(net "M_B_CPU1_SA_CA<2>")
		)
		(pad "69" smd rect
			(at -2.050034 -5.525008 270)
			(size 0.519938 1.4986)
			(layers "F.Cu" "F.Mask" "F.Paste")
			(net "GND")
		)
		(pad "70" smd rect
			(at -2.050034 -4.675124 270)
			(size 0.519938 1.4986)
			(layers "F.Cu" "F.Mask" "F.Paste")
			(net "M_B_CPU1_SA_CA<4>")
		)
		(pad "71" smd rect
			(at -2.050034 -3.824986 270)
			(size 0.519938 1.4986)
			(layers "F.Cu" "F.Mask" "F.Paste")
			(net "GND")
		)
		(pad "72" smd rect
			(at -2.050034 -2.975102 270)
			(size 0.519938 1.4986)
			(layers "F.Cu" "F.Mask" "F.Paste")
			(net "M_B_CPU1_SA_CA<6>")
		)
		(pad "73" smd rect
			(at -2.050034 -2.124964 270)
			(size 0.519938 1.4986)
			(layers "F.Cu" "F.Mask" "F.Paste")
			(net "GND")
		)
		(pad "74" smd rect
			(at -2.050034 -1.27508 270)
			(size 0.519938 1.4986)
			(layers "F.Cu" "F.Mask" "F.Paste")
			(net "M_B_CPU1_SA_PAR")
		)
		(pad "75" smd rect
			(at -2.050034 -0.424942 270)
			(size 0.519938 1.4986)
			(layers "F.Cu" "F.Mask" "F.Paste")
			(net "GND")
		)
		(pad "76" smd rect
			(at -2.050034 5.525008 270)
			(size 0.519938 1.4986)
			(layers "F.Cu" "F.Mask" "F.Paste")
			(net "M_B_CPU1_SB_CA<0>")
		)
		(pad "77" smd rect
			(at -2.050034 6.374892 270)
			(size 0.519938 1.4986)
			(layers "F.Cu" "F.Mask" "F.Paste")
			(net "GND")
		)
		(pad "78" smd rect
			(at -2.050034 7.22503 270)
			(size 0.519938 1.4986)
			(layers "F.Cu" "F.Mask" "F.Paste")
			(net "M_B_CPU1_SB_CA<2>")
		)
		(pad "79" smd rect
			(at -2.050034 8.074914 270)
			(size 0.519938 1.4986)
			(layers "F.Cu" "F.Mask" "F.Paste")
			(net "GND")
		)
		(pad "80" smd rect
			(at -2.050034 8.925052 270)
			(size 0.519938 1.4986)
			(layers "F.Cu" "F.Mask" "F.Paste")
			(net "M_B_CPU1_SB_CA<4>")
		)
		(pad "81" smd rect
			(at -2.050034 9.774936 270)
			(size 0.519938 1.4986)
			(layers "F.Cu" "F.Mask" "F.Paste")
			(net "GND")
		)
		(pad "82" smd rect
			(at -2.050034 10.625074 270)
			(size 0.519938 1.4986)
			(layers "F.Cu" "F.Mask" "F.Paste")
			(net "M_B_CPU1_SB_CA<6>")
		)
		(pad "83" smd rect
			(at -2.050034 11.474958 270)
			(size 0.519938 1.4986)
			(layers "F.Cu" "F.Mask" "F.Paste")
			(net "GND")
		)
		(pad "84" smd rect
			(at -2.050034 12.325096 270)
			(size 0.519938 1.4986)
			(layers "F.Cu" "F.Mask" "F.Paste")
			(net "M_B_CPU1_SB_CS_N<2>")
		)
		(pad "85" smd rect
			(at -2.050034 13.17498 270)
			(size 0.519938 1.4986)
			(layers "F.Cu" "F.Mask" "F.Paste")
			(net "GND")
		)
		(pad "86" smd rect
			(at -2.050034 14.025118 270)
			(size 0.519938 1.4986)
			(layers "F.Cu" "F.Mask" "F.Paste")
			(net "M_B_CPU1_SA_RSP<1>")
		)
		(pad "87" smd rect
			(at -2.050034 14.875002 270)
			(size 0.519938 1.4986)
			(layers "F.Cu" "F.Mask" "F.Paste")
			(net "M_B_CPU1_SB_RSP<1>")
		)
		(pad "88" smd rect
			(at -2.050034 15.724886 270)
			(size 0.519938 1.4986)
			(layers "F.Cu" "F.Mask" "F.Paste")
			(net "GND")
		)
		(pad "89" smd rect
			(at -2.050034 16.575024 270)
			(size 0.519938 1.4986)
			(layers "F.Cu" "F.Mask" "F.Paste")
			(net "M_B_CPU1_SB_CB<4>")
		)
		(pad "90" smd rect
			(at -2.050034 17.424908 270)
			(size 0.519938 1.4986)
			(layers "F.Cu" "F.Mask" "F.Paste")
			(net "GND")
		)
		(pad "91" smd rect
			(at -2.050034 18.275046 270)
			(size 0.519938 1.4986)
			(layers "F.Cu" "F.Mask" "F.Paste")
			(net "M_B_CPU1_SB_CB<5>")
		)
	)
)
